# S9S_MB_2U (Grand Teton) — schematic netlist excerpt (pin names and nets, part order shuffled) for the footprints in the layout excerpt that follows; sources: Cadence DE-HDL packaged netlist, KiCad conversion of 03242023_DA0F0TMBIJ0_F0T_Motherboard_J_brd_V01_OCP.brd

J16  SCONN288_ADR50017P087CC  SCONN288_ADR50017-P087CC IO  pkg DDR288S_1-1VXB  page 97
  VIN_BULK0  = P12V_S3_AUX_CPU0_NVDIMM
  RFU0  = TP_CHH_CPU0_DIMM2_FRU_0
  VIN_MGMT  = P3V3_AUX
  HSCL  = I3C_SPD_DDREFGH_CPU0_LVC1_SCL_7
  HSDA  = I3C_SPD_DDREFGH_CPU0_LVC1_SDA
  VSS0  = GND
  DQ0_A  = M_H_CPU0_SA_DQ<0>
  VSS1  = GND
  DQ1_A  = M_H_CPU0_SA_DQ<1>
  VSS2  = GND
  DQS0_A_T  = M_H_CPU0_SA_DQS_DP<0>
  DQS0_A_C  = M_H_CPU0_SA_DQS_DN<0>
  VSS3  = GND
  DQ4_A  = M_H_CPU0_SA_DQ<4>
  VSS4  = GND
  DQ5_A  = M_H_CPU0_SA_DQ<5>
  VSS5  = GND
  DQ8_A  = M_H_CPU0_SA_DQ<8>
  VSS6  = GND
  DQ9_A  = M_H_CPU0_SA_DQ<9>
  VSS7  = GND
  DQS1_A_T  = M_H_CPU0_SA_DQS_DP<1>
  DQS1_A_C  = M_H_CPU0_SA_DQS_DN<1>
  VSS8  = GND
  DQ12_A  = M_H_CPU0_SA_DQ<12>
  VSS9  = GND
  DQ13_A  = M_H_CPU0_SA_DQ<13>
  VSS10  = GND
  DQ16_A  = M_H_CPU0_SA_DQ<16>
  VSS11  = GND
  DQ17_A  = M_H_CPU0_SA_DQ<17>
  VSS12  = GND
  DQS2_A_T  = M_H_CPU0_SA_DQS_DP<2>
  DQS2_A_C  = M_H_CPU0_SA_DQS_DN<2>
  VSS13  = GND
  DQ20_A  = M_H_CPU0_SA_DQ<20>
  VSS14  = GND
  DQ21_A  = M_H_CPU0_SA_DQ<21>
  VSS15  = GND
  DQ24_A  = M_H_CPU0_SA_DQ<24>
  VSS16  = GND
  DQ25_A  = M_H_CPU0_SA_DQ<25>
  VSS17  = GND
  DQS3_A_T  = M_H_CPU0_SA_DQS_DP<3>
  DQS3_A_C  = M_H_CPU0_SA_DQS_DN<3>
  VSS18  = GND
  DQ28_A  = M_H_CPU0_SA_DQ<28>
  VSS19  = GND
  DQ29_A  = M_H_CPU0_SA_DQ<29>
  VSS20  = GND
  CB0_A  = M_H_CPU0_SA_CB<0>
  VSS21  = GND
  CB1_A  = M_H_CPU0_SA_CB<1>
  VSS22  = GND
  DQS4_A_T  = M_H_CPU0_SA_DQS_DP<4>
  DQS4_A_C  = M_H_CPU0_SA_DQS_DN<4>
  VSS23  = GND
  CB4_A  = M_H_CPU0_SA_CB<4>
  VSS24  = GND
  CB5_A  = M_H_CPU0_SA_CB<5>
  VSS25  = GND
  ALERT_N  = M_H_CPU0_ALERT_N
  VSS26  = GND
  CS0_A_N  = M_H_CPU0_SA_CS_N<2>
  VSS27  = GND
  CA0_A  = M_H_CPU0_SA_CA<0>
  VSS28  = GND
  CA2_A  = M_H_CPU0_SA_CA<2>
  VSS29  = GND
  CA4_A  = M_H_CPU0_SA_CA<4>
  VSS30  = GND
  CA6_A  = M_H_CPU0_SA_CA<6>
  VSS31  = GND
  PAR_A  = M_H_CPU0_SA_PAR
  VSS32  = GND
  CA0_B  = M_H_CPU0_SB_CA<0>
  VSS33  = GND
  CA2_B  = M_H_CPU0_SB_CA<2>
  VSS34  = GND
  CA4_B  = M_H_CPU0_SB_CA<4>
  VSS35  = GND
  CA6_B  = M_H_CPU0_SB_CA<6>
  VSS36  = GND
  CS0_B_N  = M_H_CPU0_SB_CS_N<2>
  VSS37  = GND
  \lbd||rsp_a_n\  = M_H_CPU0_SA_RSP<1>
  \lbs||rsp_b_n\  = M_H_CPU0_SB_RSP<1>
  VSS38  = GND
  CB4_B  = M_H_CPU0_SB_CB<4>
  VSS39  = GND
  CB5_B  = M_H_CPU0_SB_CB<5>
  VSS40  = GND
  \dqs9_b_t||tdqs9_b_t||dbi4_b_n\  = M_H_CPU0_SB_DQS_DP<9>
  \dqs9_b_c||tdqs9_b_c\  = M_H_CPU0_SB_DQS_DN<9>
  VSS41  = GND
  CB0_B  = M_H_CPU0_SB_CB<0>
  VSS42  = GND
  CB1_B  = M_H_CPU0_SB_CB<1>
  VSS43  = GND
  DQ0_B  = M_H_CPU0_SB_DQ<0>
  VSS44  = GND
  DQ1_B  = M_H_CPU0_SB_DQ<1>
  VSS45  = GND
  DQS0_B_T  = M_H_CPU0_SB_DQS_DP<0>
  DQS0_B_C  = M_H_CPU0_SB_DQS_DN<0>
  VSS46  = GND
  DQ4_B  = M_H_CPU0_SB_DQ<4>
  VSS47  = GND
  DQ5_B  = M_H_CPU0_SB_DQ<5>
  VSS48  = GND
  DQ8_B  = M_H_CPU0_SB_DQ<8>
  VSS49  = GND
  DQ9_B  = M_H_CPU0_SB_DQ<9>
  VSS50  = GND
  DQS1_B_T  = M_H_CPU0_SB_DQS_DP<1>
  DQS1_B_C  = M_H_CPU0_SB_DQS_DN<1>
  VSS51  = GND
  DQ12_B  = M_H_CPU0_SB_DQ<12>
  VSS52  = GND
  DQ13_B  = M_H_CPU0_SB_DQ<13>
  VSS53  = GND
  DQ16_B  = M_H_CPU0_SB_DQ<16>
  VSS54  = GND
  DQ17_B  = M_H_CPU0_SB_DQ<17>
  VSS55  = GND
  DQS2_B_T  = M_H_CPU0_SB_DQS_DP<2>
  DQS2_B_C  = M_H_CPU0_SB_DQS_DN<2>
  VSS56  = GND
  DQ20_B  = M_H_CPU0_SB_DQ<20>
  VSS57  = GND
  DQ21_B  = M_H_CPU0_SB_DQ<21>
  VSS58  = GND
  DQ24_B  = M_H_CPU0_SB_DQ<24>
  VSS59  = GND
  DQ25_B  = M_H_CPU0_SB_DQ<25>
  VSS60  = GND
  DQS3_B_T  = M_H_CPU0_SB_DQS_DP<3>
  DQS3_B_C  = M_H_CPU0_SB_DQS_DN<3>
  VSS61  = GND
  DQ28_B  = M_H_CPU0_SB_DQ<28>
  VSS62  = GND
  DQ29_B  = M_H_CPU0_SB_DQ<29>
  VSS63  = GND
  RFU1  = TP_CHH_CPU0_DIMM2_FRU_1
  VIN_BULK1  = P12V_S3_AUX_CPU0_NVDIMM
  VIN_BULK2  = P12V_S3_AUX_CPU0_NVDIMM
  \pwr_good||fail_n\  = PWRGD_CHH_CPU0_DIMM2
  HSA  = PD_CHH_CPU0_DIMM2_SAA
  RFU2  = TP_CHH_CPU0_DIMM2_FRU_2
  RFU3  = TP_CHH_CPU0_DIMM2_FRU_3
  VSS64  = GND
  DQ2_A  = M_H_CPU0_SA_DQ<2>
  VSS65  = GND
  DQ3_A  = M_H_CPU0_SA_DQ<3>
  VSS66  = GND
  \dqs5_a_c||tdqs5_a_c||dqs5_a_t||tdqs5_a_t\  = M_H_CPU0_SA_DQS_DN<5>
  \dqs5_a_t||tdqs5_a_t\  = M_H_CPU0_SA_DQS_DP<5>
  VSS67  = GND
  DQ6_A  = M_H_CPU0_SA_DQ<6>
  VSS68  = GND
  DQ7_A  = M_H_CPU0_SA_DQ<7>
  VSS69  = GND
  DQ10_A  = M_H_CPU0_SA_DQ<10>
  VSS70  = GND
  DQ11_A  = M_H_CPU0_SA_DQ<11>
  VSS71  = GND
  \dqs6_a_c||tdqs6_a_c||dqs6_a_t||tdqs6_a_t\  = M_H_CPU0_SA_DQS_DN<6>
  \dqs6_a_t||tdqs6_a_t\  = M_H_CPU0_SA_DQS_DP<6>
  VSS72  = GND
  DQ14_A  = M_H_CPU0_SA_DQ<14>
  VSS73  = GND
  DQ15_A  = M_H_CPU0_SA_DQ<15>
  VSS74  = GND
  DQ18_A  = M_H_CPU0_SA_DQ<18>
  VSS75  = GND
  DQ19_A  = M_H_CPU0_SA_DQ<19>
  VSS76  = GND
  \dqs7_a_c||tdqs7_a_c\  = M_H_CPU0_SA_DQS_DN<7>
  \dqs7_a_t||tdqs7_a_t\  = M_H_CPU0_SA_DQS_DP<7>
  VSS77  = GND
  DQ22_A  = M_H_CPU0_SA_DQ<22>
  VSS78  = GND
  DQ23_A  = M_H_CPU0_SA_DQ<23>
  VSS79  = GND
  DQ26_A  = M_H_CPU0_SA_DQ<26>
  VSS80  = GND
  DQ27_A  = M_H_CPU0_SA_DQ<27>
  VSS81  = GND
  \dqs8_a_c||tdqs8_a_c\  = M_H_CPU0_SA_DQS_DN<8>
  \dqs8_a_t||tdqs8_a_t\  = M_H_CPU0_SA_DQS_DP<8>
  VSS82  = GND
  DQ30_A  = M_H_CPU0_SA_DQ<30>
  VSS83  = GND
  DQ31_A  = M_H_CPU0_SA_DQ<31>
  VSS84  = GND
  CB2_A  = M_H_CPU0_SA_CB<2>
  VSS85  = GND
  CB3_A  = M_H_CPU0_SA_CB<3>
  VSS86  = GND
  \dqs9_a_c||tdqs9_a_c\  = M_H_CPU0_SA_DQS_DN<9>
  \dqs9_a_t||tdqs9_a_t\  = M_H_CPU0_SA_DQS_DP<9>
  VSS87  = GND
  CB6_A  = M_H_CPU0_SA_CB<6>
  VSS88  = GND
  CB7_A  = M_H_CPU0_SA_CB<7>
  VSS89  = GND
  RESET_N  = RST_M_GH_CPU0_FPGA_N
  VSS90  = GND
  CS1_A_N  = M_H_CPU0_SA_CS_N<3>
  VSS91  = GND
  CA1_A  = M_H_CPU0_SA_CA<1>
  VSS92  = GND
  CA3_A  = M_H_CPU0_SA_CA<3>
  VSS93  = GND
  CA5_A  = M_H_CPU0_SA_CA<5>
  VSS94  = GND
  CK_T  = M_H_CPU0_CLK_DP<1>
  CK_C  = M_H_CPU0_CLK_DN<1>
  VSS95  = GND
  RFU4  = TP_CHH_CPU0_DIMM2_FRU_4
  CA1_B  = M_H_CPU0_SB_CA<1>
  VSS96  = GND
  CA3_B  = M_H_CPU0_SB_CA<3>
  VSS97  = GND
  CA5_B  = M_H_CPU0_SB_CA<5>
  VSS98  = GND
  PAR_B  = M_H_CPU0_SB_PAR
  VSS99  = GND
  CS1_B_N  = M_H_CPU0_SB_CS_N<3>
  VSS100  = GND
  RFU5  = TP_CHH_CPU0_DIMM2_FRU_5
  RFU6  = TP_CHH_CPU0_DIMM2_FRU_6
  VSS101  = GND
  CB6_B  = M_H_CPU0_SB_CB<6>
  VSS102  = GND
  CB7_B  = M_H_CPU0_SB_CB<7>
  VSS103  = GND
  DQS4_B_C  = M_H_CPU0_SB_DQS_DN<4>
  DQS4_B_T  = M_H_CPU0_SB_DQS_DP<4>
  VSS104  = GND
  CB2_B  = M_H_CPU0_SB_CB<2>
  VSS105  = GND
  CB3_B  = M_H_CPU0_SB_CB<3>
  VSS106  = GND
  DQ2_B  = M_H_CPU0_SB_DQ<2>
  VSS107  = GND
  DQ3_B  = M_H_CPU0_SB_DQ<3>
  VSS108  = GND
  \dqs5_b_c||tdqs5_b_c\  = M_H_CPU0_SB_DQS_DN<5>
  \dqs5_b_t||tdqs5_b_t\  = M_H_CPU0_SB_DQS_DP<5>
  VSS109  = GND
  DQ6_B  = M_H_CPU0_SB_DQ<6>
  VSS110  = GND
  DQ7_B  = M_H_CPU0_SB_DQ<7>
  VSS111  = GND
  DQ10_B  = M_H_CPU0_SB_DQ<10>
  VSS112  = GND
  DQ11_B  = M_H_CPU0_SB_DQ<11>
  VSS113  = GND
  \dqs6_b_c||tdqs6_b_c\  = M_H_CPU0_SB_DQS_DN<6>
  \dqs6_b_t||tdqs6_b_t\  = M_H_CPU0_SB_DQS_DP<6>
  VSS114  = GND
  DQ14_B  = M_H_CPU0_SB_DQ<14>
  VSS115  = GND
  DQ15_B  = M_H_CPU0_SB_DQ<15>
  VSS116  = GND
  DQ18_B  = M_H_CPU0_SB_DQ<18>
  VSS117  = GND
  DQ19_B  = M_H_CPU0_SB_DQ<19>
  VSS118  = GND
  \dqs7_b_c||tdqs7_b_c\  = M_H_CPU0_SB_DQS_DN<7>
  \dqs7_b_t||tdqs7_b_t\  = M_H_CPU0_SB_DQS_DP<7>
  VSS119  = GND
  DQ22_B  = M_H_CPU0_SB_DQ<22>
  VSS120  = GND
  DQ23_B  = M_H_CPU0_SB_DQ<23>
  VSS121  = GND
  DQ26_B  = M_H_CPU0_SB_DQ<26>
  VSS122  = GND
  DQ27_B  = M_H_CPU0_SB_DQ<27>
  VSS123  = GND
  \dqs8_b_c||tdqs8_b_c\  = M_H_CPU0_SB_DQS_DN<8>
  \dqs8_b_t||tdqs8_b_t\  = M_H_CPU0_SB_DQS_DP<8>
  VSS124  = GND
  DQ30_B  = M_H_CPU0_SB_DQ<30>
  VSS125  = GND
  DQ31_B  = M_H_CPU0_SB_DQ<31>
  VSS126  = GND
  G1  = GND
  G2  = GND
  G3  = GND

(kicad_pcb
	(version 20260206)
	(generator "pcbnew")
	(generator_version "10.0")
	(general
		(thickness 1.6)
		(legacy_teardrops no)
	)
	(paper "A4")
	(title_block
		(title "03242023_DA0F0TMBIJ0_F0T_Motherboard_J_brd_V01_OCP.brd")
		(comment 1 "Grand Teton / footprint 1690 of 6105 (J16), pads 46-91 of 291")
	)
	(layers
		(0 "F.Cu" signal "TOP")
		(4 "In1.Cu" signal "GND")
		(6 "In2.Cu" signal "IN1")
		(8 "In3.Cu" signal "GND1")
		(10 "In4.Cu" signal "IN2")
		(12 "In5.Cu" signal "GND2")
		(14 "In6.Cu" signal "IN3")
		(16 "In7.Cu" signal "GND3")
		(18 "In8.Cu" signal "VCC")
		(20 "In9.Cu" signal "VCC1")
		(22 "In10.Cu" signal "GND4")
		(24 "In11.Cu" signal "IN4")
		(26 "In12.Cu" signal "GND5")
		(28 "In13.Cu" signal "IN5")
		(30 "In14.Cu" signal "GND6")
		(32 "In15.Cu" signal "IN6")
		(34 "In16.Cu" signal "GND7")
		(2 "B.Cu" signal "BOTTOM")
		(9 "F.Adhes" user "F.Adhesive")
		(11 "B.Adhes" user "B.Adhesive")
		(13 "F.Paste" user "Package Geometry/Pastemask Top")
		(15 "B.Paste" user "Package Geometry/Pastemask Bottom")
		(5 "F.SilkS" user "Ref Des/Silkscreen Top")
		(7 "B.SilkS" user "Ref Des/Silkscreen Bottom")
		(1 "F.Mask" user "Board Geometry/Soldermask Top")
		(3 "B.Mask" user "Board Geometry/Soldermask Bottom")
		(17 "Dwgs.User" user "User.Drawings")
		(19 "Cmts.User" user "User.Comments")
		(21 "Eco1.User" user "User.Eco1")
		(23 "Eco2.User" user "User.Eco2")
		(25 "Edge.Cuts" user "Board Geometry/Outline")
		(27 "Margin" user)
		(31 "F.CrtYd" user "Package Geometry/Place Bound Top")
		(29 "B.CrtYd" user "Package Geometry/Place Bound Bottom")
		(35 "F.Fab" user "Ref Des/Assembly Top")
		(33 "B.Fab" user "Ref Des/Assembly Bottom")
	)
	(footprint ""
		(layer "F.Cu")
		(at 454.066148 -258.091686)
		(property "Reference" "J16"
			(at -0.279908 -81.779872 0)
			(unlocked yes)
			(layer "F.SilkS")
			(effects
				(font
					(size 0.7874 0.5842)
					(thickness 0.1524)
				)
				(justify left)
			)
		)
		(property "Value" ""
			(at 0 0 0)
			(layer "F.Fab")
			(effects
				(font
					(size 1.27 1.27)
				)
			)
		)
		(duplicate_pad_numbers_are_jumpers no)
		(pad "46" smd rect
			(at -2.050034 -25.07488 270)
			(size 0.519938 1.4986)
			(layers "F.Cu" "F.Mask" "F.Paste")
			(net "GND")
		)
		(pad "47" smd rect
			(at -2.050034 -24.224996 270)
			(size 0.519938 1.4986)
			(layers "F.Cu" "F.Mask" "F.Paste")
			(net "M_H_CPU0_SA_DQ<28>")
		)
		(pad "48" smd rect
			(at -2.050034 -23.375112 270)
			(size 0.519938 1.4986)
			(layers "F.Cu" "F.Mask" "F.Paste")
			(net "GND")
		)
		(pad "49" smd rect
			(at -2.050034 -22.524974 270)
			(size 0.519938 1.4986)
			(layers "F.Cu" "F.Mask" "F.Paste")
			(net "M_H_CPU0_SA_DQ<29>")
		)
		(pad "50" smd rect
			(at -2.050034 -21.67509 270)
			(size 0.519938 1.4986)
			(layers "F.Cu" "F.Mask" "F.Paste")
			(net "GND")
		)
		(pad "51" smd rect
			(at -2.050034 -20.824952 270)
			(size 0.519938 1.4986)
			(layers "F.Cu" "F.Mask" "F.Paste")
			(net "M_H_CPU0_SA_CB<0>")
		)
		(pad "52" smd rect
			(at -2.050034 -19.975068 270)
			(size 0.519938 1.4986)
			(layers "F.Cu" "F.Mask" "F.Paste")
			(net "GND")
		)
		(pad "53" smd rect
			(at -2.050034 -19.12493 270)
			(size 0.519938 1.4986)
			(layers "F.Cu" "F.Mask" "F.Paste")
			(net "M_H_CPU0_SA_CB<1>")
		)
		(pad "54" smd rect
			(at -2.050034 -18.275046 270)
			(size 0.519938 1.4986)
			(layers "F.Cu" "F.Mask" "F.Paste")
			(net "GND")
		)
		(pad "55" smd rect
			(at -2.050034 -17.424908 270)
			(size 0.519938 1.4986)
			(layers "F.Cu" "F.Mask" "F.Paste")
			(net "M_H_CPU0_SA_DQS_DP<4>")
		)
		(pad "56" smd rect
			(at -2.050034 -16.575024 270)
			(size 0.519938 1.4986)
			(layers "F.Cu" "F.Mask" "F.Paste")
			(net "M_H_CPU0_SA_DQS_DN<4>")
		)
		(pad "57" smd rect
			(at -2.050034 -15.724886 270)
			(size 0.519938 1.4986)
			(layers "F.Cu" "F.Mask" "F.Paste")
			(net "GND")
		)
		(pad "58" smd rect
			(at -2.050034 -14.875002 270)
			(size 0.519938 1.4986)
			(layers "F.Cu" "F.Mask" "F.Paste")
			(net "M_H_CPU0_SA_CB<4>")
		)
		(pad "59" smd rect
			(at -2.050034 -14.025118 270)
			(size 0.519938 1.4986)
			(layers "F.Cu" "F.Mask" "F.Paste")
			(net "GND")
		)
		(pad "60" smd rect
			(at -2.050034 -13.17498 270)
			(size 0.519938 1.4986)
			(layers "F.Cu" "F.Mask" "F.Paste")
			(net "M_H_CPU0_SA_CB<5>")
		)
		(pad "61" smd rect
			(at -2.050034 -12.325096 270)
			(size 0.519938 1.4986)
			(layers "F.Cu" "F.Mask" "F.Paste")
			(net "GND")
		)
		(pad "62" smd rect
			(at -2.050034 -11.474958 270)
			(size 0.519938 1.4986)
			(layers "F.Cu" "F.Mask" "F.Paste")
			(net "M_H_CPU0_ALERT_N")
		)
		(pad "63" smd rect
			(at -2.050034 -10.625074 270)
			(size 0.519938 1.4986)
			(layers "F.Cu" "F.Mask" "F.Paste")
			(net "GND")
		)
		(pad "64" smd rect
			(at -2.050034 -9.774936 270)
			(size 0.519938 1.4986)
			(layers "F.Cu" "F.Mask" "F.Paste")
			(net "M_H_CPU0_SA_CS_N<2>")
		)
		(pad "65" smd rect
			(at -2.050034 -8.925052 270)
			(size 0.519938 1.4986)
			(layers "F.Cu" "F.Mask" "F.Paste")
			(net "GND")
		)
		(pad "66" smd rect
			(at -2.050034 -8.074914 270)
			(size 0.519938 1.4986)
			(layers "F.Cu" "F.Mask" "F.Paste")
			(net "M_H_CPU0_SA_CA<0>")
		)
		(pad "67" smd rect
			(at -2.050034 -7.22503 270)
			(size 0.519938 1.4986)
			(layers "F.Cu" "F.Mask" "F.Paste")
			(net "GND")
		)
		(pad "68" smd rect
			(at -2.050034 -6.374892 270)
			(size 0.519938 1.4986)
			(layers "F.Cu" "F.Mask" "F.Paste")
			(net "M_H_CPU0_SA_CA<2>")
		)
		(pad "69" smd rect
			(at -2.050034 -5.525008 270)
			(size 0.519938 1.4986)
			(layers "F.Cu" "F.Mask" "F.Paste")
			(net "GND")
		)
		(pad "70" smd rect
			(at -2.050034 -4.675124 270)
			(size 0.519938 1.4986)
			(layers "F.Cu" "F.Mask" "F.Paste")
			(net "M_H_CPU0_SA_CA<4>")
		)
		(pad "71" smd rect
			(at -2.050034 -3.824986 270)
			(size 0.519938 1.4986)
			(layers "F.Cu" "F.Mask" "F.Paste")
			(net "GND")
		)
		(pad "72" smd rect
			(at -2.050034 -2.975102 270)
			(size 0.519938 1.4986)
			(layers "F.Cu" "F.Mask" "F.Paste")
			(net "M_H_CPU0_SA_CA<6>")
		)
		(pad "73" smd rect
			(at -2.050034 -2.124964 270)
			(size 0.519938 1.4986)
			(layers "F.Cu" "F.Mask" "F.Paste")
			(net "GND")
		)
		(pad "74" smd rect
			(at -2.050034 -1.27508 270)
			(size 0.519938 1.4986)
			(layers "F.Cu" "F.Mask" "F.Paste")
			(net "M_H_CPU0_SA_PAR")
		)
		(pad "75" smd rect
			(at -2.050034 -0.424942 270)
			(size 0.519938 1.4986)
			(layers "F.Cu" "F.Mask" "F.Paste")
			(net "GND")
		)
		(pad "76" smd rect
			(at -2.050034 5.525008 270)
			(size 0.519938 1.4986)
			(layers "F.Cu" "F.Mask" "F.Paste")
			(net "M_H_CPU0_SB_CA<0>")
		)
		(pad "77" smd rect
			(at -2.050034 6.374892 270)
			(size 0.519938 1.4986)
			(layers "F.Cu" "F.Mask" "F.Paste")
			(net "GND")
		)
		(pad "78" smd rect
			(at -2.050034 7.22503 270)
			(size 0.519938 1.4986)
			(layers "F.Cu" "F.Mask" "F.Paste")
			(net "M_H_CPU0_SB_CA<2>")
		)
		(pad "79" smd rect
			(at -2.050034 8.074914 270)
			(size 0.519938 1.4986)
			(layers "F.Cu" "F.Mask" "F.Paste")
			(net "GND")
		)
		(pad "80" smd rect
			(at -2.050034 8.925052 270)
			(size 0.519938 1.4986)
			(layers "F.Cu" "F.Mask" "F.Paste")
			(net "M_H_CPU0_SB_CA<4>")
		)
		(pad "81" smd rect
			(at -2.050034 9.774936 270)
			(size 0.519938 1.4986)
			(layers "F.Cu" "F.Mask" "F.Paste")
			(net "GND")
		)
		(pad "82" smd rect
			(at -2.050034 10.625074 270)
			(size 0.519938 1.4986)
			(layers "F.Cu" "F.Mask" "F.Paste")
			(net "M_H_CPU0_SB_CA<6>")
		)
		(pad "83" smd rect
			(at -2.050034 11.474958 270)
			(size 0.519938 1.4986)
			(layers "F.Cu" "F.Mask" "F.Paste")
			(net "GND")
		)
		(pad "84" smd rect
			(at -2.050034 12.325096 270)
			(size 0.519938 1.4986)
			(layers "F.Cu" "F.Mask" "F.Paste")
			(net "M_H_CPU0_SB_CS_N<2>")
		)
		(pad "85" smd rect
			(at -2.050034 13.17498 270)
			(size 0.519938 1.4986)
			(layers "F.Cu" "F.Mask" "F.Paste")
			(net "GND")
		)
		(pad "86" smd rect
			(at -2.050034 14.025118 270)
			(size 0.519938 1.4986)
			(layers "F.Cu" "F.Mask" "F.Paste")
			(net "M_H_CPU0_SA_RSP<1>")
		)
		(pad "87" smd rect
			(at -2.050034 14.875002 270)
			(size 0.519938 1.4986)
			(layers "F.Cu" "F.Mask" "F.Paste")
			(net "M_H_CPU0_SB_RSP<1>")
		)
		(pad "88" smd rect
			(at -2.050034 15.724886 270)
			(size 0.519938 1.4986)
			(layers "F.Cu" "F.Mask" "F.Paste")
			(net "GND")
		)
		(pad "89" smd rect
			(at -2.050034 16.575024 270)
			(size 0.519938 1.4986)
			(layers "F.Cu" "F.Mask" "F.Paste")
			(net "M_H_CPU0_SB_CB<4>")
		)
		(pad "90" smd rect
			(at -2.050034 17.424908 270)
			(size 0.519938 1.4986)
			(layers "F.Cu" "F.Mask" "F.Paste")
			(net "GND")
		)
		(pad "91" smd rect
			(at -2.050034 18.275046 270)
			(size 0.519938 1.4986)
			(layers "F.Cu" "F.Mask" "F.Paste")
			(net "M_H_CPU0_SB_CB<5>")
		)
	)
)
